# BOM discovery v1 revB.xlsx — Cables (bom)
| Id | Reference | Cable color | Quantity |
| 1 | Busbar_to_powerboard | Yellow | 4 |
| 2 | Busbar_to_powerboard | Black | 4 |
